(kicad_pcb
	(version 20260206)
	(generator "pcbnew")
	(generator_version "10.0")
	(general
		(thickness 1.6)
		(legacy_teardrops no)
	)
	(paper "A4")
	(title_block
		(title "9052_F0T_PDB_Converter_Brick_F_V03_1208_1600_OCP.brd")
		(comment 1 "Grand Teton / footprints 42-44 of 578")
	)
	(layers
		(0 "F.Cu" signal "TOP")
		(4 "In1.Cu" signal "GND")
		(6 "In2.Cu" signal "IN1")
		(8 "In3.Cu" signal "GND1")
		(10 "In4.Cu" signal "VCC")
		(12 "In5.Cu" signal "VCC1")
		(14 "In6.Cu" signal "GND2")
		(16 "In7.Cu" signal "IN2")
		(18 "In8.Cu" signal "GND3")
		(2 "B.Cu" signal "BOTTOM")
		(9 "F.Adhes" user "F.Adhesive")
		(11 "B.Adhes" user "B.Adhesive")
		(13 "F.Paste" user "Package Geometry/Pastemask Top")
		(15 "B.Paste" user "Package Geometry/Pastemask Bottom")
		(5 "F.SilkS" user "Ref Des/Silkscreen Top")
		(7 "B.SilkS" user "Ref Des/Silkscreen Bottom")
		(1 "F.Mask" user "Board Geometry/Soldermask Top")
		(3 "B.Mask" user "Board Geometry/Soldermask Bottom")
		(17 "Dwgs.User" user "User.Drawings")
		(19 "Cmts.User" user "User.Comments")
		(21 "Eco1.User" user "User.Eco1")
		(23 "Eco2.User" user "User.Eco2")
		(25 "Edge.Cuts" user "Board Geometry/Outline")
		(27 "Margin" user)
		(31 "F.CrtYd" user "Package Geometry/Place Bound Top")
		(29 "B.CrtYd" user "Package Geometry/Place Bound Bottom")
		(35 "F.Fab" user "Ref Des/Assembly Top")
		(33 "B.Fab" user "Ref Des/Assembly Bottom")
	)
	(footprint ""
		(layer "F.Cu")
		(at 311.410096 -72.879966)
		(property "Reference" "J5"
			(at -1.911096 -35.170364 0)
			(unlocked yes)
			(layer "F.SilkS")
			(effects
				(font
					(size 0.7874 0.5842)
					(thickness 0.1524)
				)
			)
		)
		(property "Value" ""
			(at 0 0 0)
			(layer "F.Fab")
			(effects
				(font
					(size 1.27 1.27)
				)
			)
		)
		(duplicate_pad_numbers_are_jumpers no)
		(fp_line
			(start -6.469888 -34.36493)
			(end 14.109954 -34.36493)
			(stroke
				(width 0.1524)
				(type default)
			)
			(layer "F.SilkS")
		)
		(fp_line
			(start -6.469888 -15.385034)
			(end -6.469888 -34.36493)
			(stroke
				(width 0.1524)
				(type default)
			)
			(layer "F.SilkS")
		)
		(fp_line
			(start -6.469888 34.36493)
			(end -6.469888 -7.511034)
			(stroke
				(width 0.1524)
				(type default)
			)
			(layer "F.SilkS")
		)
		(fp_line
			(start -3.469894 -31.006034)
			(end -3.469894 -31.364936)
			(stroke
				(width 0.1524)
				(type default)
			)
			(layer "F.SilkS")
		)
		(fp_line
			(start -3.469894 25.635966)
			(end -3.469894 -26.053034)
			(stroke
				(width 0.1524)
				(type default)
			)
			(layer "F.SilkS")
		)
		(fp_line
			(start -3.469894 31.364936)
			(end -3.469894 30.969966)
			(stroke
				(width 0.1524)
				(type default)
			)
			(layer "F.SilkS")
		)
		(fp_line
			(start -3.181096 31.364936)
			(end -3.469894 31.364936)
			(stroke
				(width 0.1524)
				(type default)
			)
			(layer "F.SilkS")
		)
		(fp_line
			(start 3.930904 -31.364936)
			(end 11.10996 -31.364936)
			(stroke
				(width 0.1524)
				(type default)
			)
			(layer "F.SilkS")
		)
		(fp_line
			(start 11.10996 -31.364936)
			(end 11.10996 31.364936)
			(stroke
				(width 0.1524)
				(type default)
			)
			(layer "F.SilkS")
		)
		(fp_line
			(start 11.10996 31.364936)
			(end 3.295904 31.364936)
			(stroke
				(width 0.1524)
				(type default)
			)
			(layer "F.SilkS")
		)
		(fp_line
			(start 14.109954 -34.36493)
			(end 14.109954 34.36493)
			(stroke
				(width 0.1524)
				(type default)
			)
			(layer "F.SilkS")
		)
		(fp_line
			(start 14.109954 34.36493)
			(end -6.469888 34.36493)
			(stroke
				(width 0.1524)
				(type default)
			)
			(layer "F.SilkS")
		)
		(fp_poly
			(pts
				(xy -5.0038 -0.508) (xy -5.0038 0.508) (xy -3.9878 0)
			)
			(stroke
				(width 0)
				(type default)
			)
			(fill yes)
			(layer "F.SilkS")
		)
		(fp_line
			(start -6.469888 -34.36493)
			(end 14.109954 -34.36493)
			(stroke
				(width 0.1524)
				(type default)
			)
			(layer "B.SilkS")
		)
		(fp_line
			(start -6.469888 34.36493)
			(end -6.469888 -34.36493)
			(stroke
				(width 0.1524)
				(type default)
			)
			(layer "B.SilkS")
		)
		(fp_line
			(start 14.109954 -34.36493)
			(end 14.109954 34.36493)
			(stroke
				(width 0.1524)
				(type default)
			)
			(layer "B.SilkS")
		)
		(fp_line
			(start 14.109954 34.36493)
			(end -6.469888 34.36493)
			(stroke
				(width 0.1524)
				(type default)
			)
			(layer "B.SilkS")
		)
		(fp_line
			(start -6.469888 -34.36493)
			(end 14.109954 -34.36493)
			(stroke
				(width 0.1)
				(type default)
			)
			(layer "B.Fab")
		)
		(fp_line
			(start -6.469888 34.36493)
			(end -6.469888 -34.36493)
			(stroke
				(width 0.1)
				(type default)
			)
			(layer "B.Fab")
		)
		(fp_line
			(start 14.109954 -34.36493)
			(end 14.109954 34.36493)
			(stroke
				(width 0.1)
				(type default)
			)
			(layer "B.Fab")
		)
		(fp_line
			(start 14.109954 34.36493)
			(end -6.469888 34.36493)
			(stroke
				(width 0.1)
				(type default)
			)
			(layer "B.Fab")
		)
		(fp_line
			(start -3.469894 -31.364936)
			(end 11.10996 -31.364936)
			(stroke
				(width 0.1)
				(type default)
			)
			(layer "F.Fab")
		)
		(fp_line
			(start -3.469894 31.364936)
			(end -3.469894 -31.364936)
			(stroke
				(width 0.1)
				(type default)
			)
			(layer "F.Fab")
		)
		(fp_line
			(start 11.10996 -31.364936)
			(end 11.10996 31.364936)
			(stroke
				(width 0.1)
				(type default)
			)
			(layer "F.Fab")
		)
		(fp_line
			(start 11.10996 31.364936)
			(end -3.469894 31.364936)
			(stroke
				(width 0.1)
				(type default)
			)
			(layer "F.Fab")
		)
		(fp_poly
			(pts
				(xy -5.0038 -0.508) (xy -5.0038 0.508) (xy -3.9878 0)
			)
			(stroke
				(width 0)
				(type default)
			)
			(fill yes)
			(layer "F.Fab")
		)
		(fp_text user "PRESS-FIT"
			(at 12.598654 -1.669034 90)
			(unlocked yes)
			(layer "F.SilkS")
			(effects
				(font
					(size 1.905 1.4224)
					(thickness 0.1524)
				)
			)
		)
		(fp_text user "PRESS-FIT"
			(at 12.63015 -0.0127 270)
			(unlocked yes)
			(layer "B.SilkS")
			(effects
				(font
					(size 1.905 1.4224)
					(thickness 0.1524)
				)
				(justify mirror)
			)
		)
		(fp_text user "PRESS-FIT"
			(at 12.63015 -0.0127 270)
			(unlocked yes)
			(layer "B.Fab")
			(effects
				(font
					(size 1.905 1.4224)
					(thickness 0.1524)
				)
				(justify mirror)
			)
		)
		(fp_text user "PRESS-FIT"
			(at 12.63015 -0.0127 270)
			(unlocked yes)
			(layer "F.Fab")
			(effects
				(font
					(size 1.905 1.4224)
					(thickness 0.1524)
				)
			)
		)
		(pad "" np_thru_hole circle
			(at 0 -28.575)
			(size 0 0)
			(drill 3.2004)
			(layers "*.Cu" "*.Mask")
			(clearance 0)
		)
		(pad "" np_thru_hole circle
			(at 0 28.575)
			(size 0 0)
			(drill 3.2004)
			(layers "*.Cu" "*.Mask")
			(clearance 0)
		)
		(pad "A1" thru_hole rect
			(at 0 0)
			(size 1.52781 1.52781)
			(drill 1.01981)
			(layers "*.Cu" "*.Mask")
			(remove_unused_layers no)
			(net "P52V_BUSBAR")
			(clearance 0)
			(padstack
				(mode front_inner_back)
				(layer "Inner"
					(shape circle)
					(size 1.52781 1.52781)
					(clearance 0)
				)
				(layer "B.Cu"
					(shape rect)
					(size 1.52781 1.52781)
					(clearance 0)
				)
			)
		)
		(pad "B1" thru_hole circle
			(at 2.54 0)
			(size 1.52781 1.52781)
			(drill 1.01981)
			(layers "*.Cu" "*.Mask")
			(remove_unused_layers no)
			(net "GND_BUSBAR")
			(clearance 0)
		)
		(pad "C1" thru_hole circle
			(at 5.08 0)
			(size 1.52781 1.52781)
			(drill 1.01981)
			(layers "*.Cu" "*.Mask")
			(remove_unused_layers no)
			(net "TP_J5_C1")
			(clearance 0)
		)
		(pad "D1" thru_hole circle
			(at 7.62 0)
			(size 1.52781 1.52781)
			(drill 1.01981)
			(layers "*.Cu" "*.Mask")
			(remove_unused_layers no)
			(net "TP_J5_D1")
			(clearance 0)
		)
		(pad "P1_1" thru_hole circle
			(at 7.62 -16.51)
			(size 1.52781 1.52781)
			(drill 1.01981)
			(layers "*.Cu" "*.Mask")
			(remove_unused_layers no)
			(net "P52V_1")
			(clearance 0)
		)
		(pad "P1_2" thru_hole circle
			(at 5.08 -16.51)
			(size 1.52781 1.52781)
			(drill 1.01981)
			(layers "*.Cu" "*.Mask")
			(remove_unused_layers no)
			(net "P52V_1")
			(clearance 0)
		)
		(pad "P1_3" thru_hole circle
			(at 2.54 -16.51)
			(size 1.52781 1.52781)
			(drill 1.01981)
			(layers "*.Cu" "*.Mask")
			(remove_unused_layers no)
			(net "P52V_1")
			(clearance 0)
		)
		(pad "P1_4" thru_hole circle
			(at 0 -16.51)
			(size 1.52781 1.52781)
			(drill 1.01981)
			(layers "*.Cu" "*.Mask")
			(remove_unused_layers no)
			(net "P52V_1")
			(clearance 0)
		)
		(pad "P1_5" thru_hole circle
			(at 7.62 -13.97)
			(size 1.52781 1.52781)
			(drill 1.01981)
			(layers "*.Cu" "*.Mask")
			(remove_unused_layers no)
			(net "P52V_1")
			(clearance 0)
		)
		(pad "P1_6" thru_hole circle
			(at 5.08 -13.97)
			(size 1.52781 1.52781)
			(drill 1.01981)
			(layers "*.Cu" "*.Mask")
			(remove_unused_layers no)
			(net "P52V_1")
			(clearance 0)
		)
		(pad "P1_7" thru_hole circle
			(at 2.54 -13.97)
			(size 1.52781 1.52781)
			(drill 1.01981)
			(layers "*.Cu" "*.Mask")
			(remove_unused_layers no)
			(net "P52V_1")
			(clearance 0)
		)
		(pad "P1_8" thru_hole circle
			(at 0 -13.97)
			(size 1.52781 1.52781)
			(drill 1.01981)
			(layers "*.Cu" "*.Mask")
			(remove_unused_layers no)
			(net "P52V_1")
			(clearance 0)
		)
		(pad "P2_1" thru_hole circle
			(at 7.62 -7.62)
			(size 1.52781 1.52781)
			(drill 1.01981)
			(layers "*.Cu" "*.Mask")
			(remove_unused_layers no)
			(net "P52V_1")
			(clearance 0)
		)
		(pad "P2_2" thru_hole circle
			(at 5.08 -7.62)
			(size 1.52781 1.52781)
			(drill 1.01981)
			(layers "*.Cu" "*.Mask")
			(remove_unused_layers no)
			(net "P52V_1")
			(clearance 0)
		)
		(pad "P2_3" thru_hole circle
			(at 2.54 -7.62)
			(size 1.52781 1.52781)
			(drill 1.01981)
			(layers "*.Cu" "*.Mask")
			(remove_unused_layers no)
			(net "P52V_1")
			(clearance 0)
		)
		(pad "P2_4" thru_hole circle
			(at 0 -7.62)
			(size 1.52781 1.52781)
			(drill 1.01981)
			(layers "*.Cu" "*.Mask")
			(remove_unused_layers no)
			(net "P52V_1")
			(clearance 0)
		)
		(pad "P2_5" thru_hole circle
			(at 7.62 -5.08)
			(size 1.52781 1.52781)
			(drill 1.01981)
			(layers "*.Cu" "*.Mask")
			(remove_unused_layers no)
			(net "P52V_1")
			(clearance 0)
		)
		(pad "P2_6" thru_hole circle
			(at 5.08 -5.08)
			(size 1.52781 1.52781)
			(drill 1.01981)
			(layers "*.Cu" "*.Mask")
			(remove_unused_layers no)
			(net "P52V_1")
			(clearance 0)
		)
		(pad "P2_7" thru_hole circle
			(at 2.54 -5.08)
			(size 1.52781 1.52781)
			(drill 1.01981)
			(layers "*.Cu" "*.Mask")
			(remove_unused_layers no)
			(net "P52V_1")
			(clearance 0)
		)
		(pad "P2_8" thru_hole circle
			(at 0 -5.08)
			(size 1.52781 1.52781)
			(drill 1.01981)
			(layers "*.Cu" "*.Mask")
			(remove_unused_layers no)
			(net "P52V_1")
			(clearance 0)
		)
		(pad "P3_1" thru_hole circle
			(at 7.62 5.08)
			(size 1.52781 1.52781)
			(drill 1.01981)
			(layers "*.Cu" "*.Mask")
			(remove_unused_layers no)
			(net "GND")
			(clearance 0)
		)
		(pad "P3_2" thru_hole circle
			(at 5.08 5.08)
			(size 1.52781 1.52781)
			(drill 1.01981)
			(layers "*.Cu" "*.Mask")
			(remove_unused_layers no)
			(net "GND")
			(clearance 0)
		)
		(pad "P3_3" thru_hole circle
			(at 2.54 5.08)
			(size 1.52781 1.52781)
			(drill 1.01981)
			(layers "*.Cu" "*.Mask")
			(remove_unused_layers no)
			(net "GND")
			(clearance 0)
		)
		(pad "P3_4" thru_hole circle
			(at 0 5.08)
			(size 1.52781 1.52781)
			(drill 1.01981)
			(layers "*.Cu" "*.Mask")
			(remove_unused_layers no)
			(net "GND")
			(clearance 0)
		)
		(pad "P3_5" thru_hole circle
			(at 7.62 7.62)
			(size 1.52781 1.52781)
			(drill 1.01981)
			(layers "*.Cu" "*.Mask")
			(remove_unused_layers no)
			(net "GND")
			(clearance 0)
		)
		(pad "P3_6" thru_hole circle
			(at 5.08 7.62)
			(size 1.52781 1.52781)
			(drill 1.01981)
			(layers "*.Cu" "*.Mask")
			(remove_unused_layers no)
			(net "GND")
			(clearance 0)
		)
		(pad "P3_7" thru_hole circle
			(at 2.54 7.62)
			(size 1.52781 1.52781)
			(drill 1.01981)
			(layers "*.Cu" "*.Mask")
			(remove_unused_layers no)
			(net "GND")
			(clearance 0)
		)
		(pad "P3_8" thru_hole circle
			(at 0 7.62)
			(size 1.52781 1.52781)
			(drill 1.01981)
			(layers "*.Cu" "*.Mask")
			(remove_unused_layers no)
			(net "GND")
			(clearance 0)
		)
		(pad "P4_1" thru_hole circle
			(at 7.62 13.97)
			(size 1.52781 1.52781)
			(drill 1.01981)
			(layers "*.Cu" "*.Mask")
			(remove_unused_layers no)
			(net "GND")
			(clearance 0)
		)
		(pad "P4_2" thru_hole circle
			(at 5.08 13.97)
			(size 1.52781 1.52781)
			(drill 1.01981)
			(layers "*.Cu" "*.Mask")
			(remove_unused_layers no)
			(net "GND")
			(clearance 0)
		)
		(pad "P4_3" thru_hole circle
			(at 2.54 13.97)
			(size 1.52781 1.52781)
			(drill 1.01981)
			(layers "*.Cu" "*.Mask")
			(remove_unused_layers no)
			(net "GND")
			(clearance 0)
		)
		(pad "P4_4" thru_hole circle
			(at 0 13.97)
			(size 1.52781 1.52781)
			(drill 1.01981)
			(layers "*.Cu" "*.Mask")
			(remove_unused_layers no)
			(net "GND")
			(clearance 0)
		)
		(pad "P4_5" thru_hole circle
			(at 7.62 16.51)
			(size 1.52781 1.52781)
			(drill 1.01981)
			(layers "*.Cu" "*.Mask")
			(remove_unused_layers no)
			(net "GND")
			(clearance 0)
		)
		(pad "P4_6" thru_hole circle
			(at 5.08 16.51)
			(size 1.52781 1.52781)
			(drill 1.01981)
			(layers "*.Cu" "*.Mask")
			(remove_unused_layers no)
			(net "GND")
			(clearance 0)
		)
		(pad "P4_7" thru_hole circle
			(at 2.54 16.51)
			(size 1.52781 1.52781)
			(drill 1.01981)
			(layers "*.Cu" "*.Mask")
			(remove_unused_layers no)
			(net "GND")
			(clearance 0)
		)
		(pad "P4_8" thru_hole circle
			(at 0 16.51)
			(size 1.52781 1.52781)
			(drill 1.01981)
			(layers "*.Cu" "*.Mask")
			(remove_unused_layers no)
			(net "GND")
			(clearance 0)
		)
		(zone
			(layers "F.Cu" "B.Cu" "In1.Cu" "In2.Cu" "In3.Cu" "In4.Cu" "In5.Cu" "In6.Cu"
				"In7.Cu" "In8.Cu"
			)
			(hatch none 0.5)
			(connect_pads
				(clearance 0)
			)
			(min_thickness 0.25)
			(keepout
				(tracks not_allowed)
				(vias allowed)
				(pads allowed)
				(copperpour not_allowed)
				(footprints allowed)
			)
			(placement
				(enabled no)
				(sheetname "")
			)
			(fill
				(thermal_gap 0.5)
				(thermal_bridge_width 0.5)
				(island_removal_mode 0)
			)
			(polygon
				(pts
					(arc
						(start 315.042296 -101.454966)
						(mid 307.777896 -101.454966)
						(end 315.042296 -101.454966)
					)
				)
			)
		)
		(zone
			(layer "B.Cu")
			(hatch none 0.5)
			(connect_pads
				(clearance 0)
			)
			(min_thickness 0.25)
			(keepout
				(tracks allowed)
				(vias not_allowed)
				(pads allowed)
				(copperpour not_allowed)
				(footprints allowed)
			)
			(placement
				(enabled no)
				(sheetname "")
			)
			(fill
				(thermal_gap 0.5)
				(thermal_bridge_width 0.5)
				(island_removal_mode 0)
			)
			(polygon
				(pts
					(xy 310.582818 -90.217244) (xy 310.582818 -55.542688) (xy 319.857374 -55.542688) (xy 319.857374 -90.217244)
				)
			)
		)
	)
	(footprint ""
		(layer "F.Cu")
		(at 164.714174 -127.889)
		(property "Reference" "PC121"
			(at 0 0 0)
			(layer "F.SilkS")
			(hide yes)
			(effects
				(font
					(size 1.27 1.27)
				)
			)
		)
		(property "Value" ""
			(at 0 0 0)
			(layer "F.Fab")
			(effects
				(font
					(size 1.27 1.27)
				)
			)
		)
		(duplicate_pad_numbers_are_jumpers no)
		(fp_line
			(start -2.2098 -0.9398)
			(end 2.2098 -0.9398)
			(stroke
				(width 0.1524)
				(type default)
			)
			(layer "F.SilkS")
		)
		(fp_line
			(start -2.2098 0.9398)
			(end -2.2098 -0.9398)
			(stroke
				(width 0.1524)
				(type default)
			)
			(layer "F.SilkS")
		)
		(fp_line
			(start 2.2098 -0.9398)
			(end 2.2098 0.9398)
			(stroke
				(width 0.1524)
				(type default)
			)
			(layer "F.SilkS")
		)
		(fp_line
			(start 2.2098 0.9398)
			(end -2.2098 0.9398)
			(stroke
				(width 0.1524)
				(type default)
			)
			(layer "F.SilkS")
		)
		(fp_line
			(start -1.700022 -0.899922)
			(end 1.700022 -0.899922)
			(stroke
				(width 0.1)
				(type default)
			)
			(layer "F.Fab")
		)
		(fp_line
			(start -1.700022 0.899922)
			(end -1.700022 -0.899922)
			(stroke
				(width 0.1)
				(type default)
			)
			(layer "F.Fab")
		)
		(fp_line
			(start 1.700022 -0.899922)
			(end 1.700022 0.899922)
			(stroke
				(width 0.1)
				(type default)
			)
			(layer "F.Fab")
		)
		(fp_line
			(start 1.700022 0.899922)
			(end -1.700022 0.899922)
			(stroke
				(width 0.1)
				(type default)
			)
			(layer "F.Fab")
		)
		(pad "1" smd rect
			(at -1.4732 0 180)
			(size 1.1684 1.5748)
			(layers "F.Cu" "F.Mask" "F.Paste")
			(net "P52V_HS_FILTER")
		)
		(pad "2" smd rect
			(at 1.4732 0 180)
			(size 1.1684 1.5748)
			(layers "F.Cu" "F.Mask" "F.Paste")
			(net "GND")
		)
	)
	(footprint ""
		(layer "F.Cu")
		(at 264.808716 -36.389818)
		(property "Reference" "PC5"
			(at 0 0 0)
			(layer "F.SilkS")
			(hide yes)
			(effects
				(font
					(size 1.27 1.27)
				)
			)
		)
		(property "Value" ""
			(at 0 0 0)
			(layer "F.Fab")
			(effects
				(font
					(size 1.27 1.27)
				)
			)
		)
		(duplicate_pad_numbers_are_jumpers no)
		(fp_line
			(start -0.7874 -0.4064)
			(end 0.7874 -0.4064)
			(stroke
				(width 0.1524)
				(type default)
			)
			(layer "F.SilkS")
		)
		(fp_line
			(start -0.7874 0.4064)
			(end -0.7874 -0.4064)
			(stroke
				(width 0.1524)
				(type default)
			)
			(layer "F.SilkS")
		)
		(fp_line
			(start 0.7874 -0.4064)
			(end 0.7874 0.4064)
			(stroke
				(width 0.1524)
				(type default)
			)
			(layer "F.SilkS")
		)
		(fp_line
			(start 0.7874 0.4064)
			(end -0.7874 0.4064)
			(stroke
				(width 0.1524)
				(type default)
			)
			(layer "F.SilkS")
		)
		(fp_line
			(start -0.67945 -0.305054)
			(end -0.12065 -0.305054)
			(stroke
				(width 0.1)
				(type default)
			)
			(layer "F.Fab")
		)
		(fp_line
			(start -0.67945 0.3048)
			(end -0.67945 -0.305054)
			(stroke
				(width 0.1)
				(type default)
			)
			(layer "F.Fab")
		)
		(fp_line
			(start -0.12065 -0.305054)
			(end -0.12065 -0.2794)
			(stroke
				(width 0.1)
				(type default)
			)
			(layer "F.Fab")
		)
		(fp_line
			(start -0.12065 -0.2794)
			(end 0.12065 -0.2794)
			(stroke
				(width 0.1)
				(type default)
			)
			(layer "F.Fab")
		)
		(fp_line
			(start -0.12065 0.2794)
			(end -0.12065 0.3048)
			(stroke
				(width 0.1)
				(type default)
			)
			(layer "F.Fab")
		)
		(fp_line
			(start -0.12065 0.3048)
			(end -0.67945 0.3048)
			(stroke
				(width 0.1)
				(type default)
			)
			(layer "F.Fab")
		)
		(fp_line
			(start 0.120396 0.2794)
			(end -0.12065 0.2794)
			(stroke
				(width 0.1)
				(type default)
			)
			(layer "F.Fab")
		)
		(fp_line
			(start 0.120396 0.3048)
			(end 0.120396 0.2794)
			(stroke
				(width 0.1)
				(type default)
			)
			(layer "F.Fab")
		)
		(fp_line
			(start 0.12065 -0.3048)
			(end 0.67945 -0.3048)
			(stroke
				(width 0.1)
				(type default)
			)
			(layer "F.Fab")
		)
		(fp_line
			(start 0.12065 -0.2794)
			(end 0.12065 -0.3048)
			(stroke
				(width 0.1)
				(type default)
			)
			(layer "F.Fab")
		)
		(fp_line
			(start 0.67945 -0.3048)
			(end 0.67945 0.3048)
			(stroke
				(width 0.1)
				(type default)
			)
			(layer "F.Fab")
		)
		(fp_line
			(start 0.67945 0.3048)
			(end 0.120396 0.3048)
			(stroke
				(width 0.1)
				(type default)
			)
			(layer "F.Fab")
		)
		(pad "1" smd circle
			(at -0.40005 0)
			(size 0 0)
			(layers "F.Cu" "F.Mask" "F.Paste")
			(net "GND_FIELD_SIGNAL")
		)
		(pad "2" smd circle
			(at 0.40005 0)
			(size 0 0)
			(layers "F.Cu" "F.Mask" "F.Paste")
			(net "P52V_HS1_DVCC")
		)
	)
)
